FILE_TYPE=LIBRARY_PARTS;
primitive 'FERRITE','FERRITE_SM';
  pin
    'A':
      PIN_NUMBER='(1)';
      PINUSE='UNSPEC';
      NO_LOAD_CHECK='BOTH';
      NO_IO_CHECK='BOTH';
      ALLOW_CONNECT='TRUE';
      PIN_GROUP='0';
    'B':
      PIN_NUMBER='(2)';
      PINUSE='UNSPEC';
      NO_LOAD_CHECK='BOTH';
      NO_IO_CHECK='BOTH';
      ALLOW_CONNECT='TRUE';
      PIN_GROUP='0';
  end_pin;
  body
    PART_NAME='FERRITE';
    PHYS_DES_PREFIX='FB';
  end_body;
end_primitive;

END.
